# S9S_MB_2U (Grand Teton) — schematic netlist excerpt (pin names and nets, part order shuffled) for the footprints in the layout excerpt that follows; sources: Cadence DE-HDL packaged netlist, KiCad conversion of 03242023_DA0F0TMBIJ0_F0T_Motherboard_J_brd_V01_OCP.brd

C2050  Q_CAP  0.1UF 25V 10% X7R  pkg 0402  page 250 : A = P3V3_PDB_AUX_ADC_TIC ; B = GND
PC619  Q_CAPP  560UF 2.5V 20% OSCON  pkg THLF  page 271 : A = PVCCFA_EHV_FIVRA_CPU0 ; B = GND
R4269  Q_RES  2.2K 5% EMPTY  pkg 0402LF  page 233 : A = P3V3_AUX ; B = SMB_VR_SENSOR_3V3AUX_SCL

(kicad_pcb
	(version 20260206)
	(generator "pcbnew")
	(generator_version "10.0")
	(general
		(thickness 1.6)
		(legacy_teardrops no)
	)
	(paper "A4")
	(title_block
		(title "03242023_DA0F0TMBIJ0_F0T_Motherboard_J_brd_V01_OCP.brd")
		(comment 1 "Grand Teton / footprints 284-286 of 6105")
	)
	(layers
		(0 "F.Cu" signal "TOP")
		(4 "In1.Cu" signal "GND")
		(6 "In2.Cu" signal "IN1")
		(8 "In3.Cu" signal "GND1")
		(10 "In4.Cu" signal "IN2")
		(12 "In5.Cu" signal "GND2")
		(14 "In6.Cu" signal "IN3")
		(16 "In7.Cu" signal "GND3")
		(18 "In8.Cu" signal "VCC")
		(20 "In9.Cu" signal "VCC1")
		(22 "In10.Cu" signal "GND4")
		(24 "In11.Cu" signal "IN4")
		(26 "In12.Cu" signal "GND5")
		(28 "In13.Cu" signal "IN5")
		(30 "In14.Cu" signal "GND6")
		(32 "In15.Cu" signal "IN6")
		(34 "In16.Cu" signal "GND7")
		(2 "B.Cu" signal "BOTTOM")
		(9 "F.Adhes" user "F.Adhesive")
		(11 "B.Adhes" user "B.Adhesive")
		(13 "F.Paste" user "Package Geometry/Pastemask Top")
		(15 "B.Paste" user "Package Geometry/Pastemask Bottom")
		(5 "F.SilkS" user "Ref Des/Silkscreen Top")
		(7 "B.SilkS" user "Ref Des/Silkscreen Bottom")
		(1 "F.Mask" user "Board Geometry/Soldermask Top")
		(3 "B.Mask" user "Board Geometry/Soldermask Bottom")
		(17 "Dwgs.User" user "User.Drawings")
		(19 "Cmts.User" user "User.Comments")
		(21 "Eco1.User" user "User.Eco1")
		(23 "Eco2.User" user "User.Eco2")
		(25 "Edge.Cuts" user "Board Geometry/Outline")
		(27 "Margin" user)
		(31 "F.CrtYd" user "Package Geometry/Place Bound Top")
		(29 "B.CrtYd" user "Package Geometry/Place Bound Bottom")
		(35 "F.Fab" user "Ref Des/Assembly Top")
		(33 "B.Fab" user "Ref Des/Assembly Bottom")
	)
	(footprint ""
		(layer "F.Cu")
		(at 36.930584 -106.523282)
		(property "Reference" "C2050"
			(at 0 0 0)
			(layer "F.SilkS")
			(hide yes)
			(effects
				(font
					(size 1.27 1.27)
				)
			)
		)
		(property "Value" ""
			(at 0 0 0)
			(layer "F.Fab")
			(effects
				(font
					(size 1.27 1.27)
				)
			)
		)
		(duplicate_pad_numbers_are_jumpers no)
		(fp_line
			(start -0.7874 -0.4064)
			(end 0.7874 -0.4064)
			(stroke
				(width 0.1524)
				(type default)
			)
			(layer "F.SilkS")
		)
		(fp_line
			(start -0.7874 0.4064)
			(end -0.7874 -0.4064)
			(stroke
				(width 0.1524)
				(type default)
			)
			(layer "F.SilkS")
		)
		(fp_line
			(start 0.7874 -0.4064)
			(end 0.7874 0.4064)
			(stroke
				(width 0.1524)
				(type default)
			)
			(layer "F.SilkS")
		)
		(fp_line
			(start 0.7874 0.4064)
			(end -0.7874 0.4064)
			(stroke
				(width 0.1524)
				(type default)
			)
			(layer "F.SilkS")
		)
		(fp_line
			(start -0.67945 -0.305054)
			(end -0.12065 -0.305054)
			(stroke
				(width 0.1)
				(type default)
			)
			(layer "F.Fab")
		)
		(fp_line
			(start -0.67945 0.3048)
			(end -0.67945 -0.305054)
			(stroke
				(width 0.1)
				(type default)
			)
			(layer "F.Fab")
		)
		(fp_line
			(start -0.12065 -0.305054)
			(end -0.12065 -0.2794)
			(stroke
				(width 0.1)
				(type default)
			)
			(layer "F.Fab")
		)
		(fp_line
			(start -0.12065 -0.2794)
			(end 0.12065 -0.2794)
			(stroke
				(width 0.1)
				(type default)
			)
			(layer "F.Fab")
		)
		(fp_line
			(start -0.12065 0.2794)
			(end -0.12065 0.3048)
			(stroke
				(width 0.1)
				(type default)
			)
			(layer "F.Fab")
		)
		(fp_line
			(start -0.12065 0.3048)
			(end -0.67945 0.3048)
			(stroke
				(width 0.1)
				(type default)
			)
			(layer "F.Fab")
		)
		(fp_line
			(start 0.120396 0.2794)
			(end -0.12065 0.2794)
			(stroke
				(width 0.1)
				(type default)
			)
			(layer "F.Fab")
		)
		(fp_line
			(start 0.120396 0.3048)
			(end 0.120396 0.2794)
			(stroke
				(width 0.1)
				(type default)
			)
			(layer "F.Fab")
		)
		(fp_line
			(start 0.12065 -0.3048)
			(end 0.67945 -0.3048)
			(stroke
				(width 0.1)
				(type default)
			)
			(layer "F.Fab")
		)
		(fp_line
			(start 0.12065 -0.2794)
			(end 0.12065 -0.3048)
			(stroke
				(width 0.1)
				(type default)
			)
			(layer "F.Fab")
		)
		(fp_line
			(start 0.67945 -0.3048)
			(end 0.67945 0.3048)
			(stroke
				(width 0.1)
				(type default)
			)
			(layer "F.Fab")
		)
		(fp_line
			(start 0.67945 0.3048)
			(end 0.120396 0.3048)
			(stroke
				(width 0.1)
				(type default)
			)
			(layer "F.Fab")
		)
		(pad "1" smd circle
			(at -0.40005 0)
			(size 0 0)
			(layers "F.Cu" "F.Mask" "F.Paste")
			(net "P3V3_PDB_AUX_ADC_TIC")
		)
		(pad "2" smd circle
			(at 0.40005 0)
			(size 0 0)
			(layers "F.Cu" "F.Mask" "F.Paste")
			(net "GND")
		)
	)
	(footprint ""
		(layer "F.Cu")
		(at 299.6946 -346.700348)
		(property "Reference" "PC619"
			(at 0 0 0)
			(layer "F.SilkS")
			(hide yes)
			(effects
				(font
					(size 1.27 1.27)
				)
			)
		)
		(property "Value" ""
			(at 0 0 0)
			(layer "F.Fab")
			(effects
				(font
					(size 1.27 1.27)
				)
			)
		)
		(duplicate_pad_numbers_are_jumpers no)
		(fp_line
			(start 2.750058 0.999998)
			(end -2.750058 0.999998)
			(stroke
				(width 0.1524)
				(type default)
			)
			(layer "F.SilkS")
		)
		(fp_circle
			(center 0 0.999998)
			(end 2.750058 0.999998)
			(stroke
				(width 0.1524)
				(type default)
			)
			(fill no)
			(layer "F.SilkS")
		)
		(fp_poly
			(pts
				(arc
					(start 2.750058 0.999998)
					(mid 0 3.750056)
					(end -2.750058 0.999998)
				)
			)
			(stroke
				(width 0)
				(type default)
			)
			(fill yes)
			(layer "F.SilkS")
		)
		(fp_circle
			(center 0 0.999998)
			(end 2.750058 0.999998)
			(stroke
				(width 0.1)
				(type default)
			)
			(fill no)
			(layer "F.Fab")
		)
		(pad "1" thru_hole rect
			(at 0 0)
			(size 1.5748 1.5748)
			(drill 1.0668)
			(layers "*.Cu" "*.Mask")
			(remove_unused_layers no)
			(net "PVCCFA_EHV_FIVRA_CPU0")
			(clearance 0)
			(padstack
				(mode front_inner_back)
				(layer "Inner"
					(shape circle)
					(size 1.5748 1.5748)
					(clearance 0)
				)
				(layer "B.Cu"
					(shape rect)
					(size 1.5748 1.5748)
					(clearance 0)
				)
			)
		)
		(pad "2" thru_hole circle
			(at 0 1.999996)
			(size 1.5748 1.5748)
			(drill 1.0668)
			(layers "*.Cu" "*.Mask")
			(remove_unused_layers no)
			(net "GND")
			(clearance 0)
		)
	)
	(footprint ""
		(layer "F.Cu")
		(at 70.358 -113.756948 180)
		(property "Reference" "R4269"
			(at 0 0 180)
			(layer "F.SilkS")
			(hide yes)
			(effects
				(font
					(size 1.27 1.27)
				)
			)
		)
		(property "Value" ""
			(at 0 0 180)
			(layer "F.Fab")
			(effects
				(font
					(size 1.27 1.27)
				)
			)
		)
		(duplicate_pad_numbers_are_jumpers no)
		(fp_line
			(start 0.7874 0.4064)
			(end -0.7874 0.4064)
			(stroke
				(width 0.1524)
				(type default)
			)
			(layer "F.SilkS")
		)
		(fp_line
			(start 0.7874 -0.4064)
			(end 0.7874 0.4064)
			(stroke
				(width 0.1524)
				(type default)
			)
			(layer "F.SilkS")
		)
		(fp_line
			(start -0.7874 0.4064)
			(end -0.7874 -0.4064)
			(stroke
				(width 0.1524)
				(type default)
			)
			(layer "F.SilkS")
		)
		(fp_line
			(start -0.7874 -0.4064)
			(end 0.7874 -0.4064)
			(stroke
				(width 0.1524)
				(type default)
			)
			(layer "F.SilkS")
		)
		(fp_line
			(start 0.67945 0.3048)
			(end 0.120396 0.3048)
			(stroke
				(width 0.1)
				(type default)
			)
			(layer "F.Fab")
		)
		(fp_line
			(start 0.67945 -0.3048)
			(end 0.67945 0.3048)
			(stroke
				(width 0.1)
				(type default)
			)
			(layer "F.Fab")
		)
		(fp_line
			(start 0.12065 -0.2794)
			(end 0.12065 -0.3048)
			(stroke
				(width 0.1)
				(type default)
			)
			(layer "F.Fab")
		)
		(fp_line
			(start 0.12065 -0.3048)
			(end 0.67945 -0.3048)
			(stroke
				(width 0.1)
				(type default)
			)
			(layer "F.Fab")
		)
		(fp_line
			(start 0.120396 0.3048)
			(end 0.120396 0.2794)
			(stroke
				(width 0.1)
				(type default)
			)
			(layer "F.Fab")
		)
		(fp_line
			(start 0.120396 0.2794)
			(end -0.12065 0.2794)
			(stroke
				(width 0.1)
				(type default)
			)
			(layer "F.Fab")
		)
		(fp_line
			(start -0.12065 0.3048)
			(end -0.67945 0.3048)
			(stroke
				(width 0.1)
				(type default)
			)
			(layer "F.Fab")
		)
		(fp_line
			(start -0.12065 0.2794)
			(end -0.12065 0.3048)
			(stroke
				(width 0.1)
				(type default)
			)
			(layer "F.Fab")
		)
		(fp_line
			(start -0.12065 -0.2794)
			(end 0.12065 -0.2794)
			(stroke
				(width 0.1)
				(type default)
			)
			(layer "F.Fab")
		)
		(fp_line
			(start -0.12065 -0.305054)
			(end -0.12065 -0.2794)
			(stroke
				(width 0.1)
				(type default)
			)
			(layer "F.Fab")
		)
		(fp_line
			(start -0.67945 0.3048)
			(end -0.67945 -0.305054)
			(stroke
				(width 0.1)
				(type default)
			)
			(layer "F.Fab")
		)
		(fp_line
			(start -0.67945 -0.305054)
			(end -0.12065 -0.305054)
			(stroke
				(width 0.1)
				(type default)
			)
			(layer "F.Fab")
		)
		(pad "1" smd circle
			(at -0.40005 0 180)
			(size 0 0)
			(layers "F.Cu" "F.Mask" "F.Paste")
			(net "P3V3_AUX")
		)
		(pad "2" smd circle
			(at 0.40005 0 180)
			(size 0 0)
			(layers "F.Cu" "F.Mask" "F.Paste")
			(net "SMB_VR_SENSOR_3V3AUX_SCL")
		)
	)
)
